(kicad_pcb
	(version 20260206)
	(generator "pcbnew")
	(generator_version "10.0")
	(general
		(thickness 1.6)
		(legacy_teardrops no)
	)
	(paper "A4")
	(title_block
		(title "Bryce Canyon_F.DPB_16315-1-OCP.brd")
		(comment 1 "Bryce Canyon / footprints 924-931 of 2223")
	)
	(layers
		(0 "F.Cu" signal "TOP")
		(4 "In1.Cu" signal "L2GND")
		(6 "In2.Cu" signal "L3")
		(8 "In3.Cu" signal "L4GND")
		(10 "In4.Cu" signal "L5")
		(12 "In5.Cu" signal "L6VCC")
		(14 "In6.Cu" signal "L7VCC")
		(16 "In7.Cu" signal "L8")
		(18 "In8.Cu" signal "L9GND")
		(20 "In9.Cu" signal "L10")
		(22 "In10.Cu" signal "L11GND")
		(2 "B.Cu" signal "BOTTOM")
		(9 "F.Adhes" user "F.Adhesive")
		(11 "B.Adhes" user "B.Adhesive")
		(13 "F.Paste" user "Package Geometry/Pastemask Top")
		(15 "B.Paste" user "Package Geometry/Pastemask Bottom")
		(5 "F.SilkS" user "Ref Des/Silkscreen Top")
		(7 "B.SilkS" user "Ref Des/Silkscreen Bottom")
		(1 "F.Mask" user "Board Geometry/Soldermask Top")
		(3 "B.Mask" user "Board Geometry/Soldermask Bottom")
		(17 "Dwgs.User" user "User.Drawings")
		(19 "Cmts.User" user "User.Comments")
		(21 "Eco1.User" user "User.Eco1")
		(23 "Eco2.User" user "User.Eco2")
		(25 "Edge.Cuts" user "Board Geometry/Outline")
		(27 "Margin" user)
		(31 "F.CrtYd" user "Package Geometry/Place Bound Top")
		(29 "B.CrtYd" user "Package Geometry/Place Bound Bottom")
		(35 "F.Fab" user "Ref Des/Assembly Top")
		(33 "B.Fab" user "Ref Des/Assembly Bottom")
	)
	(footprint ""
		(layer "F.Cu")
		(at 375.5898 -145.8214)
		(property "Reference" "R1079"
			(at 0 0 0)
			(layer "F.SilkS")
			(hide yes)
			(effects
				(font
					(size 1.27 1.27)
				)
			)
		)
		(property "Value" "10KR2J-3-GP"
			(at 0.064008 -3.993896 0)
			(unlocked yes)
			(layer "F.Fab")
			(hide yes)
			(effects
				(font
					(size 1.016 1.016)
					(thickness 0.1524)
				)
			)
		)
		(property "Device Type" "R402H16"
			(at 0.064008 -5.517896 0)
			(unlocked yes)
			(layer "F.Fab")
			(hide yes)
			(effects
				(font
					(size 1.016 1.016)
					(thickness 0.1524)
				)
			)
		)
		(duplicate_pad_numbers_are_jumpers no)
		(fp_line
			(start -0.508 -0.9398)
			(end -0.508 0.9398)
			(stroke
				(width 0.1524)
				(type default)
			)
			(layer "F.SilkS")
		)
		(fp_line
			(start 0.508 -0.9398)
			(end -0.508 -0.9398)
			(stroke
				(width 0.1524)
				(type default)
			)
			(layer "F.SilkS")
		)
		(fp_rect
			(start -0.508 0.9398)
			(end 0.508 -0.9398)
			(stroke
				(width 0)
				(type default)
			)
			(fill no)
			(layer "F.CrtYd")
		)
		(fp_rect
			(start -0.508 0.9398)
			(end 0.508 -0.9398)
			(stroke
				(width 0)
				(type default)
			)
			(fill no)
			(layer "F.Fab")
		)
		(pad "1" smd custom
			(at 0 -0.4445)
			(size 0.1397 0.1397)
			(layers "F.Cu" "F.Mask" "F.Paste")
			(net "GND")
			(options
				(clearance outline)
				(anchor circle)
			)
			(primitives
				(gr_poly
					(pts
						(arc
							(start -0.1778 -0.2794)
							(mid -0.249642 -0.249642)
							(end -0.2794 -0.1778)
						)
						(arc
							(start -0.2794 0.1778)
							(mid -0.249642 0.249642)
							(end -0.1778 0.2794)
						)
						(arc
							(start 0.1778 0.2794)
							(mid 0.249642 0.249642)
							(end 0.2794 0.1778)
						)
						(arc
							(start 0.2794 -0.1778)
							(mid 0.249642 -0.249642)
							(end 0.1778 -0.2794)
						)
					)
					(width 0)
					(fill yes)
				)
			)
		)
		(pad "2" smd custom
			(at 0 0.4445)
			(size 0.1397 0.1397)
			(layers "F.Cu" "F.Mask" "F.Paste")
			(net "MB1_RETRY_R")
			(options
				(clearance outline)
				(anchor circle)
			)
			(primitives
				(gr_poly
					(pts
						(arc
							(start -0.1778 -0.2794)
							(mid -0.249642 -0.249642)
							(end -0.2794 -0.1778)
						)
						(arc
							(start -0.2794 0.1778)
							(mid -0.249642 0.249642)
							(end -0.1778 0.2794)
						)
						(arc
							(start 0.1778 0.2794)
							(mid 0.249642 0.249642)
							(end 0.2794 0.1778)
						)
						(arc
							(start 0.2794 -0.1778)
							(mid 0.249642 -0.249642)
							(end 0.1778 -0.2794)
						)
					)
					(width 0)
					(fill yes)
				)
			)
		)
	)
	(footprint ""
		(layer "F.Cu")
		(at 156.2354 -131.7244 180)
		(property "Reference" "R1038"
			(at 0 0 180)
			(layer "F.SilkS")
			(hide yes)
			(effects
				(font
					(size 1.27 1.27)
				)
			)
		)
		(property "Value" "100R2D-GP"
			(at 0.064008 -3.993896 180)
			(unlocked yes)
			(layer "F.Fab")
			(hide yes)
			(effects
				(font
					(size 1.016 1.016)
					(thickness 0.1524)
				)
			)
		)
		(property "Device Type" "R402H14"
			(at 0.064008 -5.517896 180)
			(unlocked yes)
			(layer "F.Fab")
			(hide yes)
			(effects
				(font
					(size 1.016 1.016)
					(thickness 0.1524)
				)
			)
		)
		(duplicate_pad_numbers_are_jumpers no)
		(fp_line
			(start 0.508 -0.9398)
			(end -0.508 -0.9398)
			(stroke
				(width 0.1524)
				(type default)
			)
			(layer "F.SilkS")
		)
		(fp_line
			(start -0.508 -0.9398)
			(end -0.508 0.9398)
			(stroke
				(width 0.1524)
				(type default)
			)
			(layer "F.SilkS")
		)
		(fp_rect
			(start -0.508 0.9398)
			(end 0.508 -0.9398)
			(stroke
				(width 0)
				(type default)
			)
			(fill no)
			(layer "F.CrtYd")
		)
		(fp_rect
			(start -0.508 0.9398)
			(end 0.508 -0.9398)
			(stroke
				(width 0)
				(type default)
			)
			(fill no)
			(layer "F.Fab")
		)
		(pad "1" smd custom
			(at 0 -0.4445 180)
			(size 0.1397 0.1397)
			(layers "F.Cu" "F.Mask" "F.Paste")
			(net "GND")
			(options
				(clearance outline)
				(anchor circle)
			)
			(primitives
				(gr_poly
					(pts
						(arc
							(start -0.1778 -0.2794)
							(mid -0.249642 -0.249642)
							(end -0.2794 -0.1778)
						)
						(arc
							(start -0.2794 0.1778)
							(mid -0.249642 0.249642)
							(end -0.1778 0.2794)
						)
						(arc
							(start 0.1778 0.2794)
							(mid 0.249642 0.249642)
							(end 0.2794 0.1778)
						)
						(arc
							(start 0.2794 -0.1778)
							(mid 0.249642 -0.249642)
							(end 0.1778 -0.2794)
						)
					)
					(width 0)
					(fill yes)
				)
			)
		)
		(pad "2" smd custom
			(at 0 0.4445 180)
			(size 0.1397 0.1397)
			(layers "F.Cu" "F.Mask" "F.Paste")
			(net "MB0_TEMP_E")
			(options
				(clearance outline)
				(anchor circle)
			)
			(primitives
				(gr_poly
					(pts
						(arc
							(start -0.1778 -0.2794)
							(mid -0.249642 -0.249642)
							(end -0.2794 -0.1778)
						)
						(arc
							(start -0.2794 0.1778)
							(mid -0.249642 0.249642)
							(end -0.1778 0.2794)
						)
						(arc
							(start 0.1778 0.2794)
							(mid 0.249642 0.249642)
							(end 0.2794 0.1778)
						)
						(arc
							(start 0.2794 -0.1778)
							(mid 0.249642 -0.249642)
							(end 0.1778 -0.2794)
						)
					)
					(width 0)
					(fill yes)
				)
			)
		)
	)
	(footprint ""
		(layer "F.Cu")
		(at 367.7158 -145.8214)
		(property "Reference" "R1084"
			(at 0 0 0)
			(layer "F.SilkS")
			(hide yes)
			(effects
				(font
					(size 1.27 1.27)
				)
			)
		)
		(property "Value" "100KR2F-L1-GP"
			(at 0.064008 -3.993896 0)
			(unlocked yes)
			(layer "F.Fab")
			(hide yes)
			(effects
				(font
					(size 1.016 1.016)
					(thickness 0.1524)
				)
			)
		)
		(property "Device Type" "R402H16"
			(at 0.064008 -5.517896 0)
			(unlocked yes)
			(layer "F.Fab")
			(hide yes)
			(effects
				(font
					(size 1.016 1.016)
					(thickness 0.1524)
				)
			)
		)
		(duplicate_pad_numbers_are_jumpers no)
		(fp_line
			(start -0.508 -0.9398)
			(end -0.508 0.9398)
			(stroke
				(width 0.1524)
				(type default)
			)
			(layer "F.SilkS")
		)
		(fp_line
			(start 0.508 -0.9398)
			(end -0.508 -0.9398)
			(stroke
				(width 0.1524)
				(type default)
			)
			(layer "F.SilkS")
		)
		(fp_rect
			(start -0.508 0.9398)
			(end 0.508 -0.9398)
			(stroke
				(width 0)
				(type default)
			)
			(fill no)
			(layer "F.CrtYd")
		)
		(fp_rect
			(start -0.508 0.9398)
			(end 0.508 -0.9398)
			(stroke
				(width 0)
				(type default)
			)
			(fill no)
			(layer "F.Fab")
		)
		(pad "1" smd custom
			(at 0 -0.4445)
			(size 0.1397 0.1397)
			(layers "F.Cu" "F.Mask" "F.Paste")
			(net "P12V_B_COMP")
			(options
				(clearance outline)
				(anchor circle)
			)
			(primitives
				(gr_poly
					(pts
						(arc
							(start -0.1778 -0.2794)
							(mid -0.249642 -0.249642)
							(end -0.2794 -0.1778)
						)
						(arc
							(start -0.2794 0.1778)
							(mid -0.249642 0.249642)
							(end -0.1778 0.2794)
						)
						(arc
							(start 0.1778 0.2794)
							(mid 0.249642 0.249642)
							(end 0.2794 0.1778)
						)
						(arc
							(start 0.2794 -0.1778)
							(mid 0.249642 -0.249642)
							(end 0.1778 -0.2794)
						)
					)
					(width 0)
					(fill yes)
				)
			)
		)
		(pad "2" smd custom
			(at 0 0.4445)
			(size 0.1397 0.1397)
			(layers "F.Cu" "F.Mask" "F.Paste")
			(net "MB1_P12V_PWGIN_R")
			(options
				(clearance outline)
				(anchor circle)
			)
			(primitives
				(gr_poly
					(pts
						(arc
							(start -0.1778 -0.2794)
							(mid -0.249642 -0.249642)
							(end -0.2794 -0.1778)
						)
						(arc
							(start -0.2794 0.1778)
							(mid -0.249642 0.249642)
							(end -0.1778 0.2794)
						)
						(arc
							(start 0.1778 0.2794)
							(mid 0.249642 0.249642)
							(end 0.2794 0.1778)
						)
						(arc
							(start 0.2794 -0.1778)
							(mid 0.249642 -0.249642)
							(end 0.1778 -0.2794)
						)
					)
					(width 0)
					(fill yes)
				)
			)
		)
	)
	(footprint ""
		(layer "F.Cu")
		(at 469.370918 -47.64405 90)
		(property "Reference" "D35"
			(at 0 0 90)
			(layer "F.SilkS")
			(hide yes)
			(effects
				(font
					(size 1.27 1.27)
				)
			)
		)
		(property "Value" "RB551V30-GP"
			(at 0 -6.7818 90)
			(unlocked yes)
			(layer "F.Fab")
			(hide yes)
			(effects
				(font
					(size 1.016 1.016)
					(thickness 0.1524)
				)
			)
		)
		(property "Device Type" "SOD323AKH38"
			(at 0 -8.6868 90)
			(unlocked yes)
			(layer "F.Fab")
			(hide yes)
			(effects
				(font
					(size 1.016 1.016)
					(thickness 0.1524)
				)
			)
		)
		(duplicate_pad_numbers_are_jumpers no)
		(fp_line
			(start 0.889 -1.9304)
			(end 0.889 2.159)
			(stroke
				(width 0.1524)
				(type default)
			)
			(layer "F.SilkS")
		)
		(fp_line
			(start -0.889 -1.9304)
			(end 0.889 -1.9304)
			(stroke
				(width 0.1524)
				(type default)
			)
			(layer "F.SilkS")
		)
		(fp_line
			(start 0.762 2.0574)
			(end -0.762 2.0574)
			(stroke
				(width 0.508)
				(type default)
			)
			(layer "F.SilkS")
		)
		(fp_line
			(start 0.889 2.159)
			(end -0.889 2.159)
			(stroke
				(width 0.1524)
				(type default)
			)
			(layer "F.SilkS")
		)
		(fp_line
			(start -0.889 2.159)
			(end -0.889 -1.9304)
			(stroke
				(width 0.1524)
				(type default)
			)
			(layer "F.SilkS")
		)
		(fp_rect
			(start -1.016 2.3114)
			(end 1.016 -2.0066)
			(stroke
				(width 0)
				(type default)
			)
			(fill no)
			(layer "F.CrtYd")
		)
		(fp_poly
			(pts
				(xy -1.016 -2.0066) (xy 1.016 -2.0066) (xy 1.016 2.3114) (xy -1.016 2.3114)
			)
			(stroke
				(width 0)
				(type default)
			)
			(fill no)
			(layer "F.Fab")
		)
		(pad "A" smd rect
			(at 0 -1.143 90)
			(size 0.5588 1.016)
			(layers "F.Cu" "F.Mask" "F.Paste")
			(net "SW_HDD_R35")
		)
		(pad "K" smd rect
			(at 0 1.143 90)
			(size 0.5588 1.016)
			(layers "F.Cu" "F.Mask" "F.Paste")
			(net "SW_HDD_N35")
		)
	)
	(footprint ""
		(layer "F.Cu")
		(at 367.287302 -45.735494 180)
		(property "Reference" "R860"
			(at 0 0 180)
			(layer "F.SilkS")
			(hide yes)
			(effects
				(font
					(size 1.27 1.27)
				)
			)
		)
		(property "Value" "0R2J-2-GP"
			(at 0.064008 -3.993896 180)
			(unlocked yes)
			(layer "F.Fab")
			(hide yes)
			(effects
				(font
					(size 1.016 1.016)
					(thickness 0.1524)
				)
			)
		)
		(property "Device Type" "R402H16"
			(at 0.064008 -5.517896 180)
			(unlocked yes)
			(layer "F.Fab")
			(hide yes)
			(effects
				(font
					(size 1.016 1.016)
					(thickness 0.1524)
				)
			)
		)
		(duplicate_pad_numbers_are_jumpers no)
		(fp_line
			(start 0.508 -0.9398)
			(end -0.508 -0.9398)
			(stroke
				(width 0.1524)
				(type default)
			)
			(layer "F.SilkS")
		)
		(fp_line
			(start -0.508 -0.9398)
			(end -0.508 0.9398)
			(stroke
				(width 0.1524)
				(type default)
			)
			(layer "F.SilkS")
		)
		(fp_rect
			(start -0.508 0.9398)
			(end 0.508 -0.9398)
			(stroke
				(width 0)
				(type default)
			)
			(fill no)
			(layer "F.CrtYd")
		)
		(fp_rect
			(start -0.508 0.9398)
			(end 0.508 -0.9398)
			(stroke
				(width 0)
				(type default)
			)
			(fill no)
			(layer "F.Fab")
		)
		(pad "1" smd custom
			(at 0 -0.4445 180)
			(size 0.1397 0.1397)
			(layers "F.Cu" "F.Mask" "F.Paste")
			(net "SW_HDD_G31")
			(options
				(clearance outline)
				(anchor circle)
			)
			(primitives
				(gr_poly
					(pts
						(arc
							(start -0.1778 -0.2794)
							(mid -0.249642 -0.249642)
							(end -0.2794 -0.1778)
						)
						(arc
							(start -0.2794 0.1778)
							(mid -0.249642 0.249642)
							(end -0.1778 0.2794)
						)
						(arc
							(start 0.1778 0.2794)
							(mid 0.249642 0.249642)
							(end 0.2794 0.1778)
						)
						(arc
							(start 0.2794 -0.1778)
							(mid 0.249642 -0.249642)
							(end 0.1778 -0.2794)
						)
					)
					(width 0)
					(fill yes)
				)
			)
		)
		(pad "2" smd custom
			(at 0 0.4445 180)
			(size 0.1397 0.1397)
			(layers "F.Cu" "F.Mask" "F.Paste")
			(net "SW_HDD_R31")
			(options
				(clearance outline)
				(anchor circle)
			)
			(primitives
				(gr_poly
					(pts
						(arc
							(start -0.1778 -0.2794)
							(mid -0.249642 -0.249642)
							(end -0.2794 -0.1778)
						)
						(arc
							(start -0.2794 0.1778)
							(mid -0.249642 0.249642)
							(end -0.1778 0.2794)
						)
						(arc
							(start 0.1778 0.2794)
							(mid 0.249642 0.249642)
							(end 0.2794 0.1778)
						)
						(arc
							(start 0.2794 -0.1778)
							(mid 0.249642 -0.249642)
							(end 0.1778 -0.2794)
						)
					)
					(width 0)
					(fill yes)
				)
			)
		)
	)
	(footprint ""
		(layer "F.Cu")
		(at 459.756764 -69.39026 -90)
		(property "Reference" "R913"
			(at 0 0 270)
			(layer "F.SilkS")
			(hide yes)
			(effects
				(font
					(size 1.27 1.27)
				)
			)
		)
		(property "Value" "2R6F-GP"
			(at -0.0508 -4.8514 270)
			(unlocked yes)
			(layer "F.Fab")
			(hide yes)
			(effects
				(font
					(size 1.016 1.016)
					(thickness 0.1524)
				)
			)
		)
		(property "Device Type" "R1206H26"
			(at 0 -6.3754 270)
			(unlocked yes)
			(layer "F.Fab")
			(hide yes)
			(effects
				(font
					(size 1.016 1.016)
					(thickness 0.1524)
				)
			)
		)
		(duplicate_pad_numbers_are_jumpers no)
		(fp_line
			(start -1.016 2.2352)
			(end -1.016 -2.2352)
			(stroke
				(width 0.1524)
				(type default)
			)
			(layer "F.SilkS")
		)
		(fp_line
			(start 1.016 2.2352)
			(end -1.016 2.2352)
			(stroke
				(width 0.1524)
				(type default)
			)
			(layer "F.SilkS")
		)
		(fp_line
			(start -1.016 -2.2352)
			(end 1.016 -2.2352)
			(stroke
				(width 0.1524)
				(type default)
			)
			(layer "F.SilkS")
		)
		(fp_line
			(start 1.016 -2.2352)
			(end 1.016 2.2352)
			(stroke
				(width 0.1524)
				(type default)
			)
			(layer "F.SilkS")
		)
		(fp_rect
			(start -1.0922 2.3114)
			(end 1.0922 -2.3114)
			(stroke
				(width 0)
				(type default)
			)
			(fill no)
			(layer "F.CrtYd")
		)
		(fp_poly
			(pts
				(xy -1.0922 -2.3114) (xy 1.0922 -2.3114) (xy 1.0922 2.3114) (xy -1.0922 2.3114)
			)
			(stroke
				(width 0)
				(type default)
			)
			(fill no)
			(layer "F.Fab")
		)
		(pad "1" smd rect
			(at 0 -1.397 270)
			(size 1.651 1.27)
			(layers "F.Cu" "F.Mask" "F.Paste")
			(net "P12V_HDD34")
		)
		(pad "2" smd rect
			(at 0 1.397 270)
			(size 1.651 1.27)
			(layers "F.Cu" "F.Mask" "F.Paste")
			(net "12V_PRE_34")
		)
	)
	(footprint ""
		(layer "F.Cu")
		(at 83.149948 -291.000942 -90)
		(property "Reference" "C67"
			(at 0 0 270)
			(layer "F.SilkS")
			(hide yes)
			(effects
				(font
					(size 1.27 1.27)
				)
			)
		)
		(property "Value" "SC10U16V6KX-2GP"
			(at -0.0762 -5.1308 270)
			(unlocked yes)
			(layer "F.Fab")
			(hide yes)
			(effects
				(font
					(size 1.016 1.016)
					(thickness 0.1524)
				)
			)
		)
		(property "Device Type" "C1206H71"
			(at -0.127 -6.6548 270)
			(unlocked yes)
			(layer "F.Fab")
			(hide yes)
			(effects
				(font
					(size 1.016 1.016)
					(thickness 0.1524)
				)
			)
		)
		(duplicate_pad_numbers_are_jumpers no)
		(fp_line
			(start -1.016 2.2352)
			(end -1.016 0.8382)
			(stroke
				(width 0.1524)
				(type default)
			)
			(layer "F.SilkS")
		)
		(fp_line
			(start 1.016 2.2352)
			(end -1.016 2.2352)
			(stroke
				(width 0.1524)
				(type default)
			)
			(layer "F.SilkS")
		)
		(fp_line
			(start 1.016 0.8382)
			(end 1.016 2.2352)
			(stroke
				(width 0.1524)
				(type default)
			)
			(layer "F.SilkS")
		)
		(fp_line
			(start -1.016 -0.8382)
			(end -1.016 -2.2352)
			(stroke
				(width 0.1524)
				(type default)
			)
			(layer "F.SilkS")
		)
		(fp_line
			(start -1.016 -2.2352)
			(end 1.016 -2.2352)
			(stroke
				(width 0.1524)
				(type default)
			)
			(layer "F.SilkS")
		)
		(fp_line
			(start 1.016 -2.2352)
			(end 1.016 -0.8382)
			(stroke
				(width 0.1524)
				(type default)
			)
			(layer "F.SilkS")
		)
		(fp_rect
			(start -1.0922 2.3114)
			(end 1.0922 -2.3114)
			(stroke
				(width 0)
				(type default)
			)
			(fill no)
			(layer "F.CrtYd")
		)
		(fp_poly
			(pts
				(xy 1.0922 -2.3114) (xy 1.0922 2.3114) (xy -1.0922 2.3114) (xy -1.0922 -2.3114)
			)
			(stroke
				(width 0)
				(type default)
			)
			(fill no)
			(layer "F.Fab")
		)
		(pad "1" smd rect
			(at 0 -1.397 270)
			(size 1.651 1.27)
			(layers "F.Cu" "F.Mask" "F.Paste")
			(net "P5V_HDD2")
		)
		(pad "2" smd rect
			(at 0 1.397 270)
			(size 1.651 1.27)
			(layers "F.Cu" "F.Mask" "F.Paste")
			(net "GND")
		)
	)
	(footprint ""
		(layer "F.Cu")
		(at 225.171 -365.125)
		(property "Reference" "R194"
			(at 0 0 0)
			(layer "F.SilkS")
			(hide yes)
			(effects
				(font
					(size 1.27 1.27)
				)
			)
		)
		(property "Value" "4K7R2F-GP"
			(at 0.064008 -3.993896 0)
			(unlocked yes)
			(layer "F.Fab")
			(hide yes)
			(effects
				(font
					(size 1.016 1.016)
					(thickness 0.1524)
				)
			)
		)
		(property "Device Type" "R402H16"
			(at 0.064008 -5.517896 0)
			(unlocked yes)
			(layer "F.Fab")
			(hide yes)
			(effects
				(font
					(size 1.016 1.016)
					(thickness 0.1524)
				)
			)
		)
		(duplicate_pad_numbers_are_jumpers no)
		(fp_line
			(start -0.508 -0.9398)
			(end -0.508 0.9398)
			(stroke
				(width 0.1524)
				(type default)
			)
			(layer "F.SilkS")
		)
		(fp_line
			(start 0.508 -0.9398)
			(end -0.508 -0.9398)
			(stroke
				(width 0.1524)
				(type default)
			)
			(layer "F.SilkS")
		)
		(fp_rect
			(start -0.508 0.9398)
			(end 0.508 -0.9398)
			(stroke
				(width 0)
				(type default)
			)
			(fill no)
			(layer "F.CrtYd")
		)
		(fp_rect
			(start -0.508 0.9398)
			(end 0.508 -0.9398)
			(stroke
				(width 0)
				(type default)
			)
			(fill no)
			(layer "F.Fab")
		)
		(pad "1" smd custom
			(at 0 -0.4445)
			(size 0.1397 0.1397)
			(layers "F.Cu" "F.Mask" "F.Paste")
			(net "IO_EXP3_HDD_FAULT_A2")
			(options
				(clearance outline)
				(anchor circle)
			)
			(primitives
				(gr_poly
					(pts
						(arc
							(start -0.1778 -0.2794)
							(mid -0.249642 -0.249642)
							(end -0.2794 -0.1778)
						)
						(arc
							(start -0.2794 0.1778)
							(mid -0.249642 0.249642)
							(end -0.1778 0.2794)
						)
						(arc
							(start 0.1778 0.2794)
							(mid 0.249642 0.249642)
							(end 0.2794 0.1778)
						)
						(arc
							(start 0.2794 -0.1778)
							(mid 0.249642 -0.249642)
							(end 0.1778 -0.2794)
						)
					)
					(width 0)
					(fill yes)
				)
			)
		)
		(pad "2" smd custom
			(at 0 0.4445)
			(size 0.1397 0.1397)
			(layers "F.Cu" "F.Mask" "F.Paste")
			(net "GND")
			(options
				(clearance outline)
				(anchor circle)
			)
			(primitives
				(gr_poly
					(pts
						(arc
							(start -0.1778 -0.2794)
							(mid -0.249642 -0.249642)
							(end -0.2794 -0.1778)
						)
						(arc
							(start -0.2794 0.1778)
							(mid -0.249642 0.249642)
							(end -0.1778 0.2794)
						)
						(arc
							(start 0.1778 0.2794)
							(mid 0.249642 0.249642)
							(end 0.2794 0.1778)
						)
						(arc
							(start 0.2794 -0.1778)
							(mid 0.249642 -0.249642)
							(end 0.1778 -0.2794)
						)
					)
					(width 0)
					(fill yes)
				)
			)
		)
	)
)
